(kicad_pcb
	(version 20260206)
	(generator "pcbnew")
	(generator_version "10.0")
	(general
		(thickness 1.6)
		(legacy_teardrops no)
	)
	(paper "A4")
	(title_block
		(title "peb — Lightning_PEB_BRD.brd")
		(comment 1 "Lightning (Wiwynn / Facebook NVMe JBOF) / footprints 834-841 of 2563")
	)
	(layers
		(0 "F.Cu" signal "TOP")
		(4 "In1.Cu" signal "L2GND")
		(6 "In2.Cu" signal "L3")
		(8 "In3.Cu" signal "L4VCC")
		(10 "In4.Cu" signal "L5VCC")
		(12 "In5.Cu" signal "L6")
		(14 "In6.Cu" signal "L7GND")
		(2 "B.Cu" signal "BOTTOM")
		(9 "F.Adhes" user "F.Adhesive")
		(11 "B.Adhes" user "B.Adhesive")
		(13 "F.Paste" user "Package Geometry/Pastemask Top")
		(15 "B.Paste" user "Package Geometry/Pastemask Bottom")
		(5 "F.SilkS" user "Ref Des/Silkscreen Top")
		(7 "B.SilkS" user "Ref Des/Silkscreen Bottom")
		(1 "F.Mask" user "Board Geometry/Soldermask Top")
		(3 "B.Mask" user "Board Geometry/Soldermask Bottom")
		(17 "Dwgs.User" user "User.Drawings")
		(19 "Cmts.User" user "User.Comments")
		(21 "Eco1.User" user "User.Eco1")
		(23 "Eco2.User" user "User.Eco2")
		(25 "Edge.Cuts" user "Board Geometry/Outline")
		(27 "Margin" user)
		(31 "F.CrtYd" user "Package Geometry/Place Bound Top")
		(29 "B.CrtYd" user "Package Geometry/Place Bound Bottom")
		(35 "F.Fab" user "Ref Des/Assembly Top")
		(33 "B.Fab" user "Ref Des/Assembly Bottom")
	)
	(footprint ""
		(layer "F.Cu")
		(at 246.7356 -13.3604 180)
		(property "Reference" "C464"
			(at 0 0 180)
			(layer "F.SilkS")
			(hide yes)
			(effects
				(font
					(size 1.27 1.27)
				)
			)
		)
		(property "Value" "SC4D7U16V5KX-1-GP"
			(at -0.0762 -6.1214 180)
			(unlocked yes)
			(layer "F.Fab")
			(hide yes)
			(effects
				(font
					(size 1.016 1.016)
					(thickness 0.1524)
				)
			)
		)
		(property "Device Type" "C805H56"
			(at -0.0762 -8.1534 180)
			(unlocked yes)
			(layer "F.Fab")
			(hide yes)
			(effects
				(font
					(size 1.016 1.016)
					(thickness 0.1524)
				)
			)
		)
		(duplicate_pad_numbers_are_jumpers no)
		(fp_line
			(start 0.635 0)
			(end -0.635 0)
			(stroke
				(width 0.508)
				(type default)
			)
			(layer "F.SilkS")
		)
		(fp_rect
			(start -0.9652 1.778)
			(end 0.9652 -1.778)
			(stroke
				(width 0)
				(type default)
			)
			(fill no)
			(layer "F.CrtYd")
		)
		(fp_poly
			(pts
				(xy -0.9652 -1.778) (xy 0.9652 -1.778) (xy 0.9652 1.778) (xy -0.9652 1.778)
			)
			(stroke
				(width 0)
				(type default)
			)
			(fill no)
			(layer "F.Fab")
		)
		(pad "1" smd rect
			(at 0 -0.9652 180)
			(size 1.397 1.143)
			(layers "F.Cu" "F.Mask" "F.Paste")
			(net "DUT_VDDO")
		)
		(pad "2" smd rect
			(at 0 0.9652 180)
			(size 1.397 1.143)
			(layers "F.Cu" "F.Mask" "F.Paste")
			(net "GND")
		)
	)
	(footprint ""
		(layer "F.Cu")
		(at 18.864326 -151.43988)
		(property "Reference" "U25"
			(at 0 0 0)
			(layer "F.SilkS")
			(hide yes)
			(effects
				(font
					(size 1.27 1.27)
				)
			)
		)
		(property "Value" "SN74LVC1G07DCKRG4-2-GP"
			(at -2.3368 -8.6868 0)
			(unlocked yes)
			(layer "F.Fab")
			(hide yes)
			(effects
				(font
					(size 1.016 1.016)
					(thickness 0.1524)
				)
			)
		)
		(property "Device Type" "SC70-5H44"
			(at -2.3114 -10.414 0)
			(unlocked yes)
			(layer "F.Fab")
			(hide yes)
			(effects
				(font
					(size 1.016 1.016)
					(thickness 0.1524)
				)
			)
		)
		(duplicate_pad_numbers_are_jumpers no)
		(fp_line
			(start -1.27 -1.7018)
			(end 1.27 -1.7018)
			(stroke
				(width 0.1524)
				(type default)
			)
			(layer "F.SilkS")
		)
		(fp_line
			(start -1.27 1.7018)
			(end -1.27 -1.7018)
			(stroke
				(width 0.1524)
				(type default)
			)
			(layer "F.SilkS")
		)
		(fp_line
			(start 0.6604 -1.8034)
			(end 1.3843 -1.8034)
			(stroke
				(width 0.3302)
				(type default)
			)
			(layer "F.SilkS")
		)
		(fp_line
			(start 1.27 -1.7018)
			(end 1.27 1.7018)
			(stroke
				(width 0.1524)
				(type default)
			)
			(layer "F.SilkS")
		)
		(fp_line
			(start 1.27 1.7018)
			(end -1.27 1.7018)
			(stroke
				(width 0.1524)
				(type default)
			)
			(layer "F.SilkS")
		)
		(fp_line
			(start 1.3843 -1.8034)
			(end 1.3843 -1.1176)
			(stroke
				(width 0.3302)
				(type default)
			)
			(layer "F.SilkS")
		)
		(fp_rect
			(start -1.524 1.9558)
			(end 1.524 -1.9558)
			(stroke
				(width 0)
				(type default)
			)
			(fill no)
			(layer "F.CrtYd")
		)
		(fp_poly
			(pts
				(xy -1.524 -1.9558) (xy 1.524 -1.9558) (xy 1.524 1.9558) (xy -1.524 1.9558)
			)
			(stroke
				(width 0)
				(type default)
			)
			(fill no)
			(layer "F.Fab")
		)
		(pad "1" smd rect
			(at 0.65024 -0.8255)
			(size 0.4064 1.2192)
			(layers "F.Cu" "F.Mask" "F.Paste")
			(net "Net_2089")
		)
		(pad "2" smd rect
			(at 0 -0.8255)
			(size 0.4064 1.2192)
			(layers "F.Cu" "F.Mask" "F.Paste")
			(net "FM_BMC_RESET_N")
		)
		(pad "3" smd rect
			(at -0.65024 -0.8255)
			(size 0.4064 1.2192)
			(layers "F.Cu" "F.Mask" "F.Paste")
			(net "GND")
		)
		(pad "4" smd rect
			(at -0.65024 0.8255)
			(size 0.4064 1.2192)
			(layers "F.Cu" "F.Mask" "F.Paste")
			(net "RST_BMC_DDR3_R_N")
		)
		(pad "5" smd rect
			(at 0.65024 0.8255)
			(size 0.4064 1.2192)
			(layers "F.Cu" "F.Mask" "F.Paste")
			(net "P3V3_STBY")
		)
	)
	(footprint ""
		(layer "F.Cu")
		(at 65.913 -33.782 180)
		(property "Reference" "PG3"
			(at 0 0 180)
			(layer "F.SilkS")
			(hide yes)
			(effects
				(font
					(size 1.27 1.27)
				)
			)
		)
		(property "Value" "COPPER-CLOSE-GP-U"
			(at 0.0762 -2.8702 180)
			(unlocked yes)
			(layer "F.Fab")
			(hide yes)
			(effects
				(font
					(size 1.016 1.016)
					(thickness 0.1524)
				)
			)
		)
		(property "Device Type" "CON2C-U"
			(at 0.0762 -4.3942 180)
			(unlocked yes)
			(layer "F.Fab")
			(hide yes)
			(effects
				(font
					(size 1.016 1.016)
					(thickness 0.1524)
				)
			)
		)
		(duplicate_pad_numbers_are_jumpers no)
		(fp_rect
			(start -0.9398 0.9652)
			(end 0.9398 -0.9652)
			(stroke
				(width 0)
				(type default)
			)
			(fill no)
			(layer "F.CrtYd")
		)
		(fp_rect
			(start -0.9398 0.9652)
			(end 0.9398 -0.9652)
			(stroke
				(width 0)
				(type default)
			)
			(fill no)
			(layer "F.Fab")
		)
		(pad "1" smd custom
			(at 0 -0.5334 180)
			(size 0.17145 0.17145)
			(layers "F.Cu" "F.Mask" "F.Paste")
			(net "AGND_P3V3_STBY")
			(options
				(clearance outline)
				(anchor circle)
			)
			(primitives
				(gr_poly
					(pts
						(xy -0.127 0.3429) (xy -0.127 0.1651) (xy -0.635 -0.3429) (xy 0.635 -0.3429) (xy 0.127 0.1651)
						(xy 0.127 0.3429)
					)
					(width 0)
					(fill yes)
				)
			)
		)
		(pad "2" smd custom
			(at 0 0.5334 180)
			(size 0.17145 0.17145)
			(layers "F.Cu" "F.Mask" "F.Paste")
			(net "GND")
			(options
				(clearance outline)
				(anchor circle)
			)
			(primitives
				(gr_poly
					(pts
						(xy -0.635 0.3429) (xy -0.127 -0.1651) (xy -0.127 -0.3429) (xy 0.127 -0.3429) (xy 0.127 -0.1651)
						(xy 0.635 0.3429)
					)
					(width 0)
					(fill yes)
				)
			)
		)
	)
	(footprint ""
		(layer "F.Cu")
		(at 69.699124 -183.235092 180)
		(property "Reference" "R517"
			(at 0 0 180)
			(layer "F.SilkS")
			(hide yes)
			(effects
				(font
					(size 1.27 1.27)
				)
			)
		)
		(property "Value" "10KR2F-2-GP"
			(at 0.064008 -3.993896 180)
			(unlocked yes)
			(layer "F.Fab")
			(hide yes)
			(effects
				(font
					(size 1.016 1.016)
					(thickness 0.1524)
				)
			)
		)
		(property "Device Type" "R402H16"
			(at 0.064008 -5.517896 180)
			(unlocked yes)
			(layer "F.Fab")
			(hide yes)
			(effects
				(font
					(size 1.016 1.016)
					(thickness 0.1524)
				)
			)
		)
		(duplicate_pad_numbers_are_jumpers no)
		(fp_line
			(start 0.508 -0.9398)
			(end -0.508 -0.9398)
			(stroke
				(width 0.1524)
				(type default)
			)
			(layer "F.SilkS")
		)
		(fp_line
			(start -0.508 -0.9398)
			(end -0.508 0.9398)
			(stroke
				(width 0.1524)
				(type default)
			)
			(layer "F.SilkS")
		)
		(fp_rect
			(start -0.508 0.9398)
			(end 0.508 -0.9398)
			(stroke
				(width 0)
				(type default)
			)
			(fill no)
			(layer "F.CrtYd")
		)
		(fp_rect
			(start -0.508 0.9398)
			(end 0.508 -0.9398)
			(stroke
				(width 0)
				(type default)
			)
			(fill no)
			(layer "F.Fab")
		)
		(pad "1" smd custom
			(at 0 -0.4445 180)
			(size 0.1397 0.1397)
			(layers "F.Cu" "F.Mask" "F.Paste")
			(net "GND")
			(options
				(clearance outline)
				(anchor circle)
			)
			(primitives
				(gr_poly
					(pts
						(arc
							(start -0.1778 -0.2794)
							(mid -0.249642 -0.249642)
							(end -0.2794 -0.1778)
						)
						(arc
							(start -0.2794 0.1778)
							(mid -0.249642 0.249642)
							(end -0.1778 0.2794)
						)
						(arc
							(start 0.1778 0.2794)
							(mid 0.249642 0.249642)
							(end 0.2794 0.1778)
						)
						(arc
							(start 0.2794 -0.1778)
							(mid 0.249642 -0.249642)
							(end 0.1778 -0.2794)
						)
					)
					(width 0)
					(fill yes)
				)
			)
		)
		(pad "2" smd custom
			(at 0 0.4445 180)
			(size 0.1397 0.1397)
			(layers "F.Cu" "F.Mask" "F.Paste")
			(net "IOEXP1_AD1")
			(options
				(clearance outline)
				(anchor circle)
			)
			(primitives
				(gr_poly
					(pts
						(arc
							(start -0.1778 -0.2794)
							(mid -0.249642 -0.249642)
							(end -0.2794 -0.1778)
						)
						(arc
							(start -0.2794 0.1778)
							(mid -0.249642 0.249642)
							(end -0.1778 0.2794)
						)
						(arc
							(start 0.1778 0.2794)
							(mid 0.249642 0.249642)
							(end 0.2794 0.1778)
						)
						(arc
							(start 0.2794 -0.1778)
							(mid 0.249642 -0.249642)
							(end 0.1778 -0.2794)
						)
					)
					(width 0)
					(fill yes)
				)
			)
		)
	)
	(footprint ""
		(layer "F.Cu")
		(at 215.991948 -212.420454 180)
		(property "Reference" "C109"
			(at 0 0 180)
			(layer "F.SilkS")
			(hide yes)
			(effects
				(font
					(size 1.27 1.27)
				)
			)
		)
		(property "Value" "SCD22U10V2KX-1GP"
			(at 1.1811 -2.7051 180)
			(unlocked yes)
			(layer "F.Fab")
			(hide yes)
			(effects
				(font
					(size 1.016 1.016)
					(thickness 0.1524)
				)
			)
		)
		(property "Device Type" "C402H22"
			(at 1.1811 -4.2291 180)
			(unlocked yes)
			(layer "F.Fab")
			(hide yes)
			(effects
				(font
					(size 1.016 1.016)
					(thickness 0.1524)
				)
			)
		)
		(duplicate_pad_numbers_are_jumpers no)
		(fp_rect
			(start -0.4318 0.9525)
			(end 0.4318 -0.9525)
			(stroke
				(width 0)
				(type default)
			)
			(fill no)
			(layer "F.CrtYd")
		)
		(fp_rect
			(start -0.4318 0.9525)
			(end 0.4318 -0.9525)
			(stroke
				(width 0)
				(type default)
			)
			(fill no)
			(layer "F.Fab")
		)
		(pad "1" smd custom
			(at 0 -0.4445 180)
			(size 0.1524 0.1524)
			(layers "F.Cu" "F.Mask" "F.Paste")
			(net "PCIE_TX_CAP_P38")
			(options
				(clearance outline)
				(anchor circle)
			)
			(primitives
				(gr_poly
					(pts
						(arc
							(start 0.3048 -0.2032)
							(mid 0.275042 -0.275042)
							(end 0.2032 -0.3048)
						)
						(arc
							(start -0.2032 -0.3048)
							(mid -0.275042 -0.275042)
							(end -0.3048 -0.2032)
						)
						(arc
							(start -0.3048 0.2032)
							(mid -0.275042 0.275042)
							(end -0.2032 0.3048)
						)
						(arc
							(start 0.2032 0.3048)
							(mid 0.275042 0.275042)
							(end 0.3048 0.2032)
						)
					)
					(width 0)
					(fill yes)
				)
			)
		)
		(pad "2" smd custom
			(at 0 0.4445 180)
			(size 0.1524 0.1524)
			(layers "F.Cu" "F.Mask" "F.Paste")
			(net "PCIE_TX_P38")
			(options
				(clearance outline)
				(anchor circle)
			)
			(primitives
				(gr_poly
					(pts
						(arc
							(start 0.3048 -0.2032)
							(mid 0.275042 -0.275042)
							(end 0.2032 -0.3048)
						)
						(arc
							(start -0.2032 -0.3048)
							(mid -0.275042 -0.275042)
							(end -0.3048 -0.2032)
						)
						(arc
							(start -0.3048 0.2032)
							(mid -0.275042 0.275042)
							(end -0.2032 0.3048)
						)
						(arc
							(start 0.2032 0.3048)
							(mid 0.275042 0.275042)
							(end 0.3048 0.2032)
						)
					)
					(width 0)
					(fill yes)
				)
			)
		)
	)
	(footprint ""
		(layer "F.Cu")
		(at 253.04242 -11.364976 180)
		(property "Reference" "R3602"
			(at 0 0 180)
			(layer "F.SilkS")
			(hide yes)
			(effects
				(font
					(size 1.27 1.27)
				)
			)
		)
		(property "Value" "1KR2F-3-GP"
			(at 0.064008 -3.993896 180)
			(unlocked yes)
			(layer "F.Fab")
			(hide yes)
			(effects
				(font
					(size 1.016 1.016)
					(thickness 0.1524)
				)
			)
		)
		(property "Device Type" "R402H16"
			(at 0.064008 -5.517896 180)
			(unlocked yes)
			(layer "F.Fab")
			(hide yes)
			(effects
				(font
					(size 1.016 1.016)
					(thickness 0.1524)
				)
			)
		)
		(duplicate_pad_numbers_are_jumpers no)
		(fp_line
			(start 0.508 -0.9398)
			(end -0.508 -0.9398)
			(stroke
				(width 0.1524)
				(type default)
			)
			(layer "F.SilkS")
		)
		(fp_line
			(start -0.508 -0.9398)
			(end -0.508 0.9398)
			(stroke
				(width 0.1524)
				(type default)
			)
			(layer "F.SilkS")
		)
		(fp_rect
			(start -0.508 0.9398)
			(end 0.508 -0.9398)
			(stroke
				(width 0)
				(type default)
			)
			(fill no)
			(layer "F.CrtYd")
		)
		(fp_rect
			(start -0.508 0.9398)
			(end 0.508 -0.9398)
			(stroke
				(width 0)
				(type default)
			)
			(fill no)
			(layer "F.Fab")
		)
		(pad "1" smd custom
			(at 0 -0.4445 180)
			(size 0.1397 0.1397)
			(layers "F.Cu" "F.Mask" "F.Paste")
			(net "MAX6654_ADD1")
			(options
				(clearance outline)
				(anchor circle)
			)
			(primitives
				(gr_poly
					(pts
						(arc
							(start -0.1778 -0.2794)
							(mid -0.249642 -0.249642)
							(end -0.2794 -0.1778)
						)
						(arc
							(start -0.2794 0.1778)
							(mid -0.249642 0.249642)
							(end -0.1778 0.2794)
						)
						(arc
							(start 0.1778 0.2794)
							(mid 0.249642 0.249642)
							(end 0.2794 0.1778)
						)
						(arc
							(start 0.2794 -0.1778)
							(mid 0.249642 -0.249642)
							(end 0.1778 -0.2794)
						)
					)
					(width 0)
					(fill yes)
				)
			)
		)
		(pad "2" smd custom
			(at 0 0.4445 180)
			(size 0.1397 0.1397)
			(layers "F.Cu" "F.Mask" "F.Paste")
			(net "GND")
			(options
				(clearance outline)
				(anchor circle)
			)
			(primitives
				(gr_poly
					(pts
						(arc
							(start -0.1778 -0.2794)
							(mid -0.249642 -0.249642)
							(end -0.2794 -0.1778)
						)
						(arc
							(start -0.2794 0.1778)
							(mid -0.249642 0.249642)
							(end -0.1778 0.2794)
						)
						(arc
							(start 0.1778 0.2794)
							(mid 0.249642 0.249642)
							(end 0.2794 0.1778)
						)
						(arc
							(start 0.2794 -0.1778)
							(mid 0.249642 -0.249642)
							(end 0.1778 -0.2794)
						)
					)
					(width 0)
					(fill yes)
				)
			)
		)
	)
	(footprint ""
		(layer "F.Cu")
		(at 7.874 -106.68)
		(property "Reference" "PC80"
			(at 0 0 0)
			(layer "F.SilkS")
			(hide yes)
			(effects
				(font
					(size 1.27 1.27)
				)
			)
		)
		(property "Value" "SC10U6D3V5KX-4GP"
			(at -0.0762 -6.1214 0)
			(unlocked yes)
			(layer "F.Fab")
			(hide yes)
			(effects
				(font
					(size 1.016 1.016)
					(thickness 0.1524)
				)
			)
		)
		(property "Device Type" "C805H58"
			(at -0.0762 -8.1534 0)
			(unlocked yes)
			(layer "F.Fab")
			(hide yes)
			(effects
				(font
					(size 1.016 1.016)
					(thickness 0.1524)
				)
			)
		)
		(duplicate_pad_numbers_are_jumpers no)
		(fp_line
			(start 0.635 0)
			(end -0.635 0)
			(stroke
				(width 0.508)
				(type default)
			)
			(layer "F.SilkS")
		)
		(fp_rect
			(start -0.9652 1.778)
			(end 0.9652 -1.778)
			(stroke
				(width 0)
				(type default)
			)
			(fill no)
			(layer "F.CrtYd")
		)
		(fp_poly
			(pts
				(xy -0.9652 -1.778) (xy 0.9652 -1.778) (xy 0.9652 1.778) (xy -0.9652 1.778)
			)
			(stroke
				(width 0)
				(type default)
			)
			(fill no)
			(layer "F.Fab")
		)
		(pad "1" smd rect
			(at 0 -0.9652)
			(size 1.397 1.143)
			(layers "F.Cu" "F.Mask" "F.Paste")
			(net "VR_P1V26_STBY_BIAS")
		)
		(pad "2" smd rect
			(at 0 0.9652)
			(size 1.397 1.143)
			(layers "F.Cu" "F.Mask" "F.Paste")
			(net "GND")
		)
	)
	(footprint ""
		(layer "F.Cu")
		(at 235.966 -6.92658 -90)
		(property "Reference" "C322"
			(at 0 0 270)
			(layer "F.SilkS")
			(hide yes)
			(effects
				(font
					(size 1.27 1.27)
				)
			)
		)
		(property "Value" "SCD1U16V2KX-3GP"
			(at 1.1811 -2.7051 270)
			(unlocked yes)
			(layer "F.Fab")
			(hide yes)
			(effects
				(font
					(size 1.016 1.016)
					(thickness 0.1524)
				)
			)
		)
		(property "Device Type" "C402H22"
			(at 1.1811 -4.2291 270)
			(unlocked yes)
			(layer "F.Fab")
			(hide yes)
			(effects
				(font
					(size 1.016 1.016)
					(thickness 0.1524)
				)
			)
		)
		(duplicate_pad_numbers_are_jumpers no)
		(fp_rect
			(start -0.4318 0.9525)
			(end 0.4318 -0.9525)
			(stroke
				(width 0)
				(type default)
			)
			(fill no)
			(layer "F.CrtYd")
		)
		(fp_rect
			(start -0.4318 0.9525)
			(end 0.4318 -0.9525)
			(stroke
				(width 0)
				(type default)
			)
			(fill no)
			(layer "F.Fab")
		)
		(pad "1" smd custom
			(at 0 -0.4445 270)
			(size 0.1524 0.1524)
			(layers "F.Cu" "F.Mask" "F.Paste")
			(net "DP_RST_N")
			(options
				(clearance outline)
				(anchor circle)
			)
			(primitives
				(gr_poly
					(pts
						(arc
							(start 0.3048 -0.2032)
							(mid 0.275042 -0.275042)
							(end 0.2032 -0.3048)
						)
						(arc
							(start -0.2032 -0.3048)
							(mid -0.275042 -0.275042)
							(end -0.3048 -0.2032)
						)
						(arc
							(start -0.3048 0.2032)
							(mid -0.275042 0.275042)
							(end -0.2032 0.3048)
						)
						(arc
							(start 0.2032 0.3048)
							(mid 0.275042 0.275042)
							(end 0.3048 0.2032)
						)
					)
					(width 0)
					(fill yes)
				)
			)
		)
		(pad "2" smd custom
			(at 0 0.4445 270)
			(size 0.1524 0.1524)
			(layers "F.Cu" "F.Mask" "F.Paste")
			(net "GND")
			(options
				(clearance outline)
				(anchor circle)
			)
			(primitives
				(gr_poly
					(pts
						(arc
							(start 0.3048 -0.2032)
							(mid 0.275042 -0.275042)
							(end 0.2032 -0.3048)
						)
						(arc
							(start -0.2032 -0.3048)
							(mid -0.275042 -0.275042)
							(end -0.3048 -0.2032)
						)
						(arc
							(start -0.3048 0.2032)
							(mid -0.275042 0.275042)
							(end -0.2032 0.3048)
						)
						(arc
							(start 0.2032 0.3048)
							(mid 0.275042 0.275042)
							(end 0.3048 0.2032)
						)
					)
					(width 0)
					(fill yes)
				)
			)
		)
	)
)
